# SCM (Grand Teton) — schematic netlist excerpt (pin names and nets, part order shuffled) for the footprints in the layout excerpt that follows; sources: Cadence DE-HDL packaged netlist, KiCad conversion of 12092022_DA0F0TMDCD0_F0T_Management_Board_D_brd_V3_OCP.brd

R460  Q_RES  33.2 1% CHIP  pkg 0402LF  page 13 : A = SPI_BMC_TPM_CS2_R_N ; B = SPI_BMC_TPM_CS2_R1_N
R268  Q_RES  4.7K 1% CHIP  pkg 0402LF  page 27 : A = P3V3_AUX ; B = SMB_BMC_ALERT3_N

(kicad_pcb
	(version 20260206)
	(generator "pcbnew")
	(generator_version "10.0")
	(general
		(thickness 1.6)
		(legacy_teardrops no)
	)
	(paper "A4")
	(title_block
		(title "12092022_DA0F0TMDCD0_F0T_Management_Board_D_brd_V3_OCP.brd")
		(comment 1 "Grand Teton / footprints 485-486 of 1440")
	)
	(layers
		(0 "F.Cu" signal "TOP")
		(4 "In1.Cu" signal "GND")
		(6 "In2.Cu" signal "IN1")
		(8 "In3.Cu" signal "GND1")
		(10 "In4.Cu" signal "IN2")
		(12 "In5.Cu" signal "VCC")
		(14 "In6.Cu" signal "VCC1")
		(16 "In7.Cu" signal "IN3")
		(18 "In8.Cu" signal "GND2")
		(20 "In9.Cu" signal "IN4")
		(22 "In10.Cu" signal "GND3")
		(2 "B.Cu" signal "BOTTOM")
		(9 "F.Adhes" user "F.Adhesive")
		(11 "B.Adhes" user "B.Adhesive")
		(13 "F.Paste" user "Package Geometry/Pastemask Top")
		(15 "B.Paste" user "Package Geometry/Pastemask Bottom")
		(5 "F.SilkS" user "Ref Des/Silkscreen Top")
		(7 "B.SilkS" user "Ref Des/Silkscreen Bottom")
		(1 "F.Mask" user "Board Geometry/Soldermask Top")
		(3 "B.Mask" user "Board Geometry/Soldermask Bottom")
		(17 "Dwgs.User" user "User.Drawings")
		(19 "Cmts.User" user "User.Comments")
		(21 "Eco1.User" user "User.Eco1")
		(23 "Eco2.User" user "User.Eco2")
		(25 "Edge.Cuts" user "Board Geometry/Outline")
		(27 "Margin" user)
		(31 "F.CrtYd" user "Package Geometry/Place Bound Top")
		(29 "B.CrtYd" user "Package Geometry/Place Bound Bottom")
		(35 "F.Fab" user "Ref Des/Assembly Top")
		(33 "B.Fab" user "Ref Des/Assembly Bottom")
	)
	(footprint ""
		(layer "F.Cu")
		(at 69.4055 -69.596 -90)
		(property "Reference" "R460"
			(at 0 0 270)
			(layer "F.SilkS")
			(hide yes)
			(effects
				(font
					(size 1.27 1.27)
				)
			)
		)
		(property "Value" ""
			(at 0 0 270)
			(layer "F.Fab")
			(effects
				(font
					(size 1.27 1.27)
				)
			)
		)
		(duplicate_pad_numbers_are_jumpers no)
		(fp_line
			(start -0.7874 0.4064)
			(end -0.7874 -0.4064)
			(stroke
				(width 0.1524)
				(type default)
			)
			(layer "F.SilkS")
		)
		(fp_line
			(start 0.7874 0.4064)
			(end -0.7874 0.4064)
			(stroke
				(width 0.1524)
				(type default)
			)
			(layer "F.SilkS")
		)
		(fp_line
			(start -0.7874 -0.4064)
			(end 0.7874 -0.4064)
			(stroke
				(width 0.1524)
				(type default)
			)
			(layer "F.SilkS")
		)
		(fp_line
			(start 0.7874 -0.4064)
			(end 0.7874 0.4064)
			(stroke
				(width 0.1524)
				(type default)
			)
			(layer "F.SilkS")
		)
		(fp_line
			(start -0.67945 0.3048)
			(end -0.67945 -0.305054)
			(stroke
				(width 0.1)
				(type default)
			)
			(layer "F.Fab")
		)
		(fp_line
			(start -0.12065 0.3048)
			(end -0.67945 0.3048)
			(stroke
				(width 0.1)
				(type default)
			)
			(layer "F.Fab")
		)
		(fp_line
			(start 0.120396 0.3048)
			(end 0.120396 0.2794)
			(stroke
				(width 0.1)
				(type default)
			)
			(layer "F.Fab")
		)
		(fp_line
			(start 0.67945 0.3048)
			(end 0.120396 0.3048)
			(stroke
				(width 0.1)
				(type default)
			)
			(layer "F.Fab")
		)
		(fp_line
			(start -0.12065 0.2794)
			(end -0.12065 0.3048)
			(stroke
				(width 0.1)
				(type default)
			)
			(layer "F.Fab")
		)
		(fp_line
			(start 0.120396 0.2794)
			(end -0.12065 0.2794)
			(stroke
				(width 0.1)
				(type default)
			)
			(layer "F.Fab")
		)
		(fp_line
			(start -0.12065 -0.2794)
			(end 0.12065 -0.2794)
			(stroke
				(width 0.1)
				(type default)
			)
			(layer "F.Fab")
		)
		(fp_line
			(start 0.12065 -0.2794)
			(end 0.12065 -0.3048)
			(stroke
				(width 0.1)
				(type default)
			)
			(layer "F.Fab")
		)
		(fp_line
			(start 0.12065 -0.3048)
			(end 0.67945 -0.3048)
			(stroke
				(width 0.1)
				(type default)
			)
			(layer "F.Fab")
		)
		(fp_line
			(start 0.67945 -0.3048)
			(end 0.67945 0.3048)
			(stroke
				(width 0.1)
				(type default)
			)
			(layer "F.Fab")
		)
		(fp_line
			(start -0.67945 -0.305054)
			(end -0.12065 -0.305054)
			(stroke
				(width 0.1)
				(type default)
			)
			(layer "F.Fab")
		)
		(fp_line
			(start -0.12065 -0.305054)
			(end -0.12065 -0.2794)
			(stroke
				(width 0.1)
				(type default)
			)
			(layer "F.Fab")
		)
		(pad "1" smd circle
			(at -0.40005 0 270)
			(size 0 0)
			(layers "F.Cu" "F.Mask" "F.Paste")
			(net "SPI_BMC_TPM_CS2_R_N")
		)
		(pad "2" smd circle
			(at 0.40005 0 270)
			(size 0 0)
			(layers "F.Cu" "F.Mask" "F.Paste")
			(net "SPI_BMC_TPM_CS2_R1_N")
		)
	)
	(footprint ""
		(layer "F.Cu")
		(at 37.6936 -42.1894 -90)
		(property "Reference" "R268"
			(at 0 0 270)
			(layer "F.SilkS")
			(hide yes)
			(effects
				(font
					(size 1.27 1.27)
				)
			)
		)
		(property "Value" ""
			(at 0 0 270)
			(layer "F.Fab")
			(effects
				(font
					(size 1.27 1.27)
				)
			)
		)
		(duplicate_pad_numbers_are_jumpers no)
		(fp_line
			(start -0.7874 0.4064)
			(end -0.7874 -0.4064)
			(stroke
				(width 0.1524)
				(type default)
			)
			(layer "F.SilkS")
		)
		(fp_line
			(start 0.7874 0.4064)
			(end -0.7874 0.4064)
			(stroke
				(width 0.1524)
				(type default)
			)
			(layer "F.SilkS")
		)
		(fp_line
			(start -0.7874 -0.4064)
			(end 0.7874 -0.4064)
			(stroke
				(width 0.1524)
				(type default)
			)
			(layer "F.SilkS")
		)
		(fp_line
			(start 0.7874 -0.4064)
			(end 0.7874 0.4064)
			(stroke
				(width 0.1524)
				(type default)
			)
			(layer "F.SilkS")
		)
		(fp_line
			(start -0.67945 0.3048)
			(end -0.67945 -0.305054)
			(stroke
				(width 0.1)
				(type default)
			)
			(layer "F.Fab")
		)
		(fp_line
			(start -0.12065 0.3048)
			(end -0.67945 0.3048)
			(stroke
				(width 0.1)
				(type default)
			)
			(layer "F.Fab")
		)
		(fp_line
			(start 0.120396 0.3048)
			(end 0.120396 0.2794)
			(stroke
				(width 0.1)
				(type default)
			)
			(layer "F.Fab")
		)
		(fp_line
			(start 0.67945 0.3048)
			(end 0.120396 0.3048)
			(stroke
				(width 0.1)
				(type default)
			)
			(layer "F.Fab")
		)
		(fp_line
			(start -0.12065 0.2794)
			(end -0.12065 0.3048)
			(stroke
				(width 0.1)
				(type default)
			)
			(layer "F.Fab")
		)
		(fp_line
			(start 0.120396 0.2794)
			(end -0.12065 0.2794)
			(stroke
				(width 0.1)
				(type default)
			)
			(layer "F.Fab")
		)
		(fp_line
			(start -0.12065 -0.2794)
			(end 0.12065 -0.2794)
			(stroke
				(width 0.1)
				(type default)
			)
			(layer "F.Fab")
		)
		(fp_line
			(start 0.12065 -0.2794)
			(end 0.12065 -0.3048)
			(stroke
				(width 0.1)
				(type default)
			)
			(layer "F.Fab")
		)
		(fp_line
			(start 0.12065 -0.3048)
			(end 0.67945 -0.3048)
			(stroke
				(width 0.1)
				(type default)
			)
			(layer "F.Fab")
		)
		(fp_line
			(start 0.67945 -0.3048)
			(end 0.67945 0.3048)
			(stroke
				(width 0.1)
				(type default)
			)
			(layer "F.Fab")
		)
		(fp_line
			(start -0.67945 -0.305054)
			(end -0.12065 -0.305054)
			(stroke
				(width 0.1)
				(type default)
			)
			(layer "F.Fab")
		)
		(fp_line
			(start -0.12065 -0.305054)
			(end -0.12065 -0.2794)
			(stroke
				(width 0.1)
				(type default)
			)
			(layer "F.Fab")
		)
		(pad "1" smd circle
			(at -0.40005 0 270)
			(size 0 0)
			(layers "F.Cu" "F.Mask" "F.Paste")
			(net "P3V3_AUX")
		)
		(pad "2" smd circle
			(at 0.40005 0 270)
			(size 0 0)
			(layers "F.Cu" "F.Mask" "F.Paste")
			(net "SMB_BMC_ALERT3_N")
		)
	)
)
